(kicad_pcb
	(version 20260206)
	(generator "pcbnew")
	(generator_version "10.0")
	(general
		(thickness 1.6)
		(legacy_teardrops no)
	)
	(paper "A4")
	(title_block
		(title "baseboard — 13948-1b.1110WZS1818.brd")
		(comment 1 "Honey Badger (Wiwynn) / footprints 274-280 of 2523")
	)
	(layers
		(0 "F.Cu" signal "TOP")
		(4 "In1.Cu" signal "L2GND")
		(6 "In2.Cu" signal "L3")
		(8 "In3.Cu" signal "L4VCC")
		(10 "In4.Cu" signal "L5VCC")
		(12 "In5.Cu" signal "L6")
		(14 "In6.Cu" signal "L7GND")
		(2 "B.Cu" signal "BOTTOM")
		(9 "F.Adhes" user "F.Adhesive")
		(11 "B.Adhes" user "B.Adhesive")
		(13 "F.Paste" user "Package Geometry/Pastemask Top")
		(15 "B.Paste" user "Package Geometry/Pastemask Bottom")
		(5 "F.SilkS" user "Ref Des/Silkscreen Top")
		(7 "B.SilkS" user "Ref Des/Silkscreen Bottom")
		(1 "F.Mask" user "Board Geometry/Soldermask Top")
		(3 "B.Mask" user "Board Geometry/Soldermask Bottom")
		(17 "Dwgs.User" user "User.Drawings")
		(19 "Cmts.User" user "User.Comments")
		(21 "Eco1.User" user "User.Eco1")
		(23 "Eco2.User" user "User.Eco2")
		(25 "Edge.Cuts" user "Board Geometry/Outline")
		(27 "Margin" user)
		(31 "F.CrtYd" user "Package Geometry/Place Bound Top")
		(29 "B.CrtYd" user "Package Geometry/Place Bound Bottom")
		(35 "F.Fab" user "Ref Des/Assembly Top")
		(33 "B.Fab" user "Ref Des/Assembly Bottom")
	)
	(footprint ""
		(layer "F.Cu")
		(at 115.678966 -25.781 -90)
		(property "Reference" "SLED26"
			(at 0 0 270)
			(layer "F.SilkS")
			(hide yes)
			(effects
				(font
					(size 1.27 1.27)
				)
			)
		)
		(property "Value" "LED-YG-51-GP"
			(at -2.6924 -1.4224 270)
			(unlocked yes)
			(layer "F.Fab")
			(hide yes)
			(effects
				(font
					(size 1.016 1.016)
					(thickness 0.1524)
				)
			)
		)
		(property "Device Type" "LED1608AKH40"
			(at -2.6924 -2.9464 270)
			(unlocked yes)
			(layer "F.Fab")
			(hide yes)
			(effects
				(font
					(size 1.016 1.016)
					(thickness 0.1524)
				)
			)
		)
		(duplicate_pad_numbers_are_jumpers no)
		(fp_line
			(start -0.7493 1.651)
			(end -0.7493 1.1811)
			(stroke
				(width 0.3302)
				(type default)
			)
			(layer "F.SilkS")
		)
		(fp_line
			(start 0.7493 1.651)
			(end 0.7493 1.1811)
			(stroke
				(width 0.3302)
				(type default)
			)
			(layer "F.SilkS")
		)
		(fp_line
			(start -0.5969 1.5494)
			(end 0.5842 1.5494)
			(stroke
				(width 0.508)
				(type default)
			)
			(layer "F.SilkS")
		)
		(fp_line
			(start -0.6604 1.3716)
			(end -0.6604 -1.3716)
			(stroke
				(width 0.1524)
				(type default)
			)
			(layer "F.SilkS")
		)
		(fp_line
			(start 0.6604 1.3716)
			(end -0.6604 1.3716)
			(stroke
				(width 0.1524)
				(type default)
			)
			(layer "F.SilkS")
		)
		(fp_line
			(start -0.6604 -1.3716)
			(end 0.6604 -1.3716)
			(stroke
				(width 0.1524)
				(type default)
			)
			(layer "F.SilkS")
		)
		(fp_line
			(start 0.6604 -1.3716)
			(end 0.6604 1.3716)
			(stroke
				(width 0.1524)
				(type default)
			)
			(layer "F.SilkS")
		)
		(fp_rect
			(start -0.6223 1.3335)
			(end 0.6223 -1.3335)
			(stroke
				(width 0)
				(type default)
			)
			(fill no)
			(layer "F.CrtYd")
		)
		(fp_rect
			(start -0.6223 1.3335)
			(end 0.6223 -1.3335)
			(stroke
				(width 0)
				(type default)
			)
			(fill no)
			(layer "F.Fab")
		)
		(pad "A" smd custom
			(at 0 -0.762 270)
			(size 0.2159 0.2159)
			(layers "F.Cu" "F.Mask" "F.Paste")
			(net "SYS_ERROR_LED_R")
			(options
				(clearance outline)
				(anchor circle)
			)
			(primitives
				(gr_poly
					(pts
						(arc
							(start -0.3302 -0.4318)
							(mid -0.402042 -0.402042)
							(end -0.4318 -0.3302)
						)
						(arc
							(start -0.4318 0.3302)
							(mid -0.402042 0.402042)
							(end -0.3302 0.4318)
						)
						(arc
							(start 0.3302 0.4318)
							(mid 0.402042 0.402042)
							(end 0.4318 0.3302)
						)
						(arc
							(start 0.4318 -0.3302)
							(mid 0.402042 -0.402042)
							(end 0.3302 -0.4318)
						)
					)
					(width 0)
					(fill yes)
				)
			)
		)
		(pad "K" smd custom
			(at 0 0.762 270)
			(size 0.2159 0.2159)
			(layers "F.Cu" "F.Mask" "F.Paste")
			(net "SYS_ERROR_LED_D")
			(options
				(clearance outline)
				(anchor circle)
			)
			(primitives
				(gr_poly
					(pts
						(arc
							(start -0.3302 -0.4318)
							(mid -0.402042 -0.402042)
							(end -0.4318 -0.3302)
						)
						(arc
							(start -0.4318 0.3302)
							(mid -0.402042 0.402042)
							(end -0.3302 0.4318)
						)
						(arc
							(start 0.3302 0.4318)
							(mid 0.402042 0.402042)
							(end 0.4318 0.3302)
						)
						(arc
							(start 0.4318 -0.3302)
							(mid 0.402042 -0.402042)
							(end 0.3302 -0.4318)
						)
					)
					(width 0)
					(fill yes)
				)
			)
		)
	)
	(footprint ""
		(layer "F.Cu")
		(at 114.497612 -222.885)
		(property "Reference" "SR878"
			(at 0 0 0)
			(layer "F.SilkS")
			(hide yes)
			(effects
				(font
					(size 1.27 1.27)
				)
			)
		)
		(property "Value" "0R2J-2-GP"
			(at 0.064008 -3.993896 0)
			(unlocked yes)
			(layer "F.Fab")
			(hide yes)
			(effects
				(font
					(size 1.016 1.016)
					(thickness 0.1524)
				)
			)
		)
		(property "Device Type" "R402H16"
			(at 0.064008 -5.517896 0)
			(unlocked yes)
			(layer "F.Fab")
			(hide yes)
			(effects
				(font
					(size 1.016 1.016)
					(thickness 0.1524)
				)
			)
		)
		(duplicate_pad_numbers_are_jumpers no)
		(fp_line
			(start -0.508 -0.9398)
			(end -0.508 0.9398)
			(stroke
				(width 0.1524)
				(type default)
			)
			(layer "F.SilkS")
		)
		(fp_line
			(start 0.508 -0.9398)
			(end -0.508 -0.9398)
			(stroke
				(width 0.1524)
				(type default)
			)
			(layer "F.SilkS")
		)
		(fp_rect
			(start -0.508 0.9398)
			(end 0.508 -0.9398)
			(stroke
				(width 0)
				(type default)
			)
			(fill no)
			(layer "F.CrtYd")
		)
		(fp_rect
			(start -0.508 0.9398)
			(end 0.508 -0.9398)
			(stroke
				(width 0)
				(type default)
			)
			(fill no)
			(layer "F.Fab")
		)
		(pad "1" smd custom
			(at 0 -0.4445)
			(size 0.1397 0.1397)
			(layers "F.Cu" "F.Mask" "F.Paste")
			(net "SAS_HDD_CONN_SER_TX8_P")
			(options
				(clearance outline)
				(anchor circle)
			)
			(primitives
				(gr_poly
					(pts
						(arc
							(start -0.1778 -0.2794)
							(mid -0.249642 -0.249642)
							(end -0.2794 -0.1778)
						)
						(arc
							(start -0.2794 0.1778)
							(mid -0.249642 0.249642)
							(end -0.1778 0.2794)
						)
						(arc
							(start 0.1778 0.2794)
							(mid 0.249642 0.249642)
							(end 0.2794 0.1778)
						)
						(arc
							(start 0.2794 -0.1778)
							(mid 0.249642 -0.249642)
							(end 0.1778 -0.2794)
						)
					)
					(width 0)
					(fill yes)
				)
			)
		)
		(pad "2" smd custom
			(at 0 0.4445)
			(size 0.1397 0.1397)
			(layers "F.Cu" "F.Mask" "F.Paste")
			(net "SAS_HDD_CONN_TX8_P")
			(options
				(clearance outline)
				(anchor circle)
			)
			(primitives
				(gr_poly
					(pts
						(arc
							(start -0.1778 -0.2794)
							(mid -0.249642 -0.249642)
							(end -0.2794 -0.1778)
						)
						(arc
							(start -0.2794 0.1778)
							(mid -0.249642 0.249642)
							(end -0.1778 0.2794)
						)
						(arc
							(start 0.1778 0.2794)
							(mid 0.249642 0.249642)
							(end 0.2794 0.1778)
						)
						(arc
							(start 0.2794 -0.1778)
							(mid 0.249642 -0.249642)
							(end 0.1778 -0.2794)
						)
					)
					(width 0)
					(fill yes)
				)
			)
		)
	)
	(footprint ""
		(layer "F.Cu")
		(at 320.294 -198.882 -90)
		(property "Reference" "R546"
			(at 0 0 270)
			(layer "F.SilkS")
			(hide yes)
			(effects
				(font
					(size 1.27 1.27)
				)
			)
		)
		(property "Value" "10KR2F-2-GP"
			(at 0.064008 -3.993896 270)
			(unlocked yes)
			(layer "F.Fab")
			(hide yes)
			(effects
				(font
					(size 1.016 1.016)
					(thickness 0.1524)
				)
			)
		)
		(property "Device Type" "R402H16"
			(at 0.064008 -5.517896 270)
			(unlocked yes)
			(layer "F.Fab")
			(hide yes)
			(effects
				(font
					(size 1.016 1.016)
					(thickness 0.1524)
				)
			)
		)
		(duplicate_pad_numbers_are_jumpers no)
		(fp_line
			(start -0.508 -0.9398)
			(end -0.508 0.9398)
			(stroke
				(width 0.1524)
				(type default)
			)
			(layer "F.SilkS")
		)
		(fp_line
			(start 0.508 -0.9398)
			(end -0.508 -0.9398)
			(stroke
				(width 0.1524)
				(type default)
			)
			(layer "F.SilkS")
		)
		(fp_rect
			(start -0.508 0.9398)
			(end 0.508 -0.9398)
			(stroke
				(width 0)
				(type default)
			)
			(fill no)
			(layer "F.CrtYd")
		)
		(fp_rect
			(start -0.508 0.9398)
			(end 0.508 -0.9398)
			(stroke
				(width 0)
				(type default)
			)
			(fill no)
			(layer "F.Fab")
		)
		(pad "1" smd custom
			(at 0 -0.4445 270)
			(size 0.1397 0.1397)
			(layers "F.Cu" "F.Mask" "F.Paste")
			(net "P3V3_STBY")
			(options
				(clearance outline)
				(anchor circle)
			)
			(primitives
				(gr_poly
					(pts
						(arc
							(start -0.1778 -0.2794)
							(mid -0.249642 -0.249642)
							(end -0.2794 -0.1778)
						)
						(arc
							(start -0.2794 0.1778)
							(mid -0.249642 0.249642)
							(end -0.1778 0.2794)
						)
						(arc
							(start 0.1778 0.2794)
							(mid 0.249642 0.249642)
							(end 0.2794 0.1778)
						)
						(arc
							(start 0.2794 -0.1778)
							(mid 0.249642 -0.249642)
							(end 0.1778 -0.2794)
						)
					)
					(width 0)
					(fill yes)
				)
			)
		)
		(pad "2" smd custom
			(at 0 0.4445 270)
			(size 0.1397 0.1397)
			(layers "F.Cu" "F.Mask" "F.Paste")
			(net "BMC_JTAG_L_EN")
			(options
				(clearance outline)
				(anchor circle)
			)
			(primitives
				(gr_poly
					(pts
						(arc
							(start -0.1778 -0.2794)
							(mid -0.249642 -0.249642)
							(end -0.2794 -0.1778)
						)
						(arc
							(start -0.2794 0.1778)
							(mid -0.249642 0.249642)
							(end -0.1778 0.2794)
						)
						(arc
							(start 0.1778 0.2794)
							(mid 0.249642 0.249642)
							(end 0.2794 0.1778)
						)
						(arc
							(start 0.2794 -0.1778)
							(mid 0.249642 -0.249642)
							(end 0.1778 -0.2794)
						)
					)
					(width 0)
					(fill yes)
				)
			)
		)
	)
	(footprint ""
		(layer "F.Cu")
		(at 47.5742 -114.7572 180)
		(property "Reference" "SR942"
			(at 0 0 180)
			(layer "F.SilkS")
			(hide yes)
			(effects
				(font
					(size 1.27 1.27)
				)
			)
		)
		(property "Value" "0R2J-2-GP"
			(at 0.064008 -3.993896 180)
			(unlocked yes)
			(layer "F.Fab")
			(hide yes)
			(effects
				(font
					(size 1.016 1.016)
					(thickness 0.1524)
				)
			)
		)
		(property "Device Type" "R402H16"
			(at 0.064008 -5.517896 180)
			(unlocked yes)
			(layer "F.Fab")
			(hide yes)
			(effects
				(font
					(size 1.016 1.016)
					(thickness 0.1524)
				)
			)
		)
		(duplicate_pad_numbers_are_jumpers no)
		(fp_line
			(start 0.508 -0.9398)
			(end -0.508 -0.9398)
			(stroke
				(width 0.1524)
				(type default)
			)
			(layer "F.SilkS")
		)
		(fp_line
			(start -0.508 -0.9398)
			(end -0.508 0.9398)
			(stroke
				(width 0.1524)
				(type default)
			)
			(layer "F.SilkS")
		)
		(fp_rect
			(start -0.508 0.9398)
			(end 0.508 -0.9398)
			(stroke
				(width 0)
				(type default)
			)
			(fill no)
			(layer "F.CrtYd")
		)
		(fp_rect
			(start -0.508 0.9398)
			(end 0.508 -0.9398)
			(stroke
				(width 0)
				(type default)
			)
			(fill no)
			(layer "F.Fab")
		)
		(pad "1" smd custom
			(at 0 -0.4445 180)
			(size 0.1397 0.1397)
			(layers "F.Cu" "F.Mask" "F.Paste")
			(net "BMC_R_TXD5")
			(options
				(clearance outline)
				(anchor circle)
			)
			(primitives
				(gr_poly
					(pts
						(arc
							(start -0.1778 -0.2794)
							(mid -0.249642 -0.249642)
							(end -0.2794 -0.1778)
						)
						(arc
							(start -0.2794 0.1778)
							(mid -0.249642 0.249642)
							(end -0.1778 0.2794)
						)
						(arc
							(start 0.1778 0.2794)
							(mid 0.249642 0.249642)
							(end 0.2794 0.1778)
						)
						(arc
							(start 0.2794 -0.1778)
							(mid 0.249642 -0.249642)
							(end 0.1778 -0.2794)
						)
					)
					(width 0)
					(fill yes)
				)
			)
		)
		(pad "2" smd custom
			(at 0 0.4445 180)
			(size 0.1397 0.1397)
			(layers "F.Cu" "F.Mask" "F.Paste")
			(net "BMC_TXD5")
			(options
				(clearance outline)
				(anchor circle)
			)
			(primitives
				(gr_poly
					(pts
						(arc
							(start -0.1778 -0.2794)
							(mid -0.249642 -0.249642)
							(end -0.2794 -0.1778)
						)
						(arc
							(start -0.2794 0.1778)
							(mid -0.249642 0.249642)
							(end -0.1778 0.2794)
						)
						(arc
							(start 0.1778 0.2794)
							(mid 0.249642 0.249642)
							(end 0.2794 0.1778)
						)
						(arc
							(start 0.2794 -0.1778)
							(mid 0.249642 -0.249642)
							(end 0.1778 -0.2794)
						)
					)
					(width 0)
					(fill yes)
				)
			)
		)
	)
	(footprint ""
		(layer "F.Cu")
		(at 95.70847 -106.045 -90)
		(property "Reference" "SR792"
			(at 0 0 270)
			(layer "F.SilkS")
			(hide yes)
			(effects
				(font
					(size 1.27 1.27)
				)
			)
		)
		(property "Value" "0R2J-2-GP"
			(at 0.064008 -3.993896 270)
			(unlocked yes)
			(layer "F.Fab")
			(hide yes)
			(effects
				(font
					(size 1.016 1.016)
					(thickness 0.1524)
				)
			)
		)
		(property "Device Type" "R402H16"
			(at 0.064008 -5.517896 270)
			(unlocked yes)
			(layer "F.Fab")
			(hide yes)
			(effects
				(font
					(size 1.016 1.016)
					(thickness 0.1524)
				)
			)
		)
		(duplicate_pad_numbers_are_jumpers no)
		(fp_line
			(start -0.508 -0.9398)
			(end -0.508 0.9398)
			(stroke
				(width 0.1524)
				(type default)
			)
			(layer "F.SilkS")
		)
		(fp_line
			(start 0.508 -0.9398)
			(end -0.508 -0.9398)
			(stroke
				(width 0.1524)
				(type default)
			)
			(layer "F.SilkS")
		)
		(fp_rect
			(start -0.508 0.9398)
			(end 0.508 -0.9398)
			(stroke
				(width 0)
				(type default)
			)
			(fill no)
			(layer "F.CrtYd")
		)
		(fp_rect
			(start -0.508 0.9398)
			(end 0.508 -0.9398)
			(stroke
				(width 0)
				(type default)
			)
			(fill no)
			(layer "F.Fab")
		)
		(pad "1" smd custom
			(at 0 -0.4445 270)
			(size 0.1397 0.1397)
			(layers "F.Cu" "F.Mask" "F.Paste")
			(net "SMART_RX")
			(options
				(clearance outline)
				(anchor circle)
			)
			(primitives
				(gr_poly
					(pts
						(arc
							(start -0.1778 -0.2794)
							(mid -0.249642 -0.249642)
							(end -0.2794 -0.1778)
						)
						(arc
							(start -0.2794 0.1778)
							(mid -0.249642 0.249642)
							(end -0.1778 0.2794)
						)
						(arc
							(start 0.1778 0.2794)
							(mid 0.249642 0.249642)
							(end 0.2794 0.1778)
						)
						(arc
							(start 0.2794 -0.1778)
							(mid 0.249642 -0.249642)
							(end 0.1778 -0.2794)
						)
					)
					(width 0)
					(fill yes)
				)
			)
		)
		(pad "2" smd custom
			(at 0 0.4445 270)
			(size 0.1397 0.1397)
			(layers "F.Cu" "F.Mask" "F.Paste")
			(net "SAS_SMART_RX")
			(options
				(clearance outline)
				(anchor circle)
			)
			(primitives
				(gr_poly
					(pts
						(arc
							(start -0.1778 -0.2794)
							(mid -0.249642 -0.249642)
							(end -0.2794 -0.1778)
						)
						(arc
							(start -0.2794 0.1778)
							(mid -0.249642 0.249642)
							(end -0.1778 0.2794)
						)
						(arc
							(start 0.1778 0.2794)
							(mid 0.249642 0.249642)
							(end 0.2794 0.1778)
						)
						(arc
							(start 0.2794 -0.1778)
							(mid 0.249642 -0.249642)
							(end 0.1778 -0.2794)
						)
					)
					(width 0)
					(fill yes)
				)
			)
		)
	)
	(footprint ""
		(layer "F.Cu")
		(at 166.233856 -110.880652 90)
		(property "Reference" "R610"
			(at 0 0 90)
			(layer "F.SilkS")
			(hide yes)
			(effects
				(font
					(size 1.27 1.27)
				)
			)
		)
		(property "Value" "4K7R2F-GP"
			(at 0.064008 -3.993896 90)
			(unlocked yes)
			(layer "F.Fab")
			(hide yes)
			(effects
				(font
					(size 1.016 1.016)
					(thickness 0.1524)
				)
			)
		)
		(property "Device Type" "R402H16"
			(at 0.064008 -5.517896 90)
			(unlocked yes)
			(layer "F.Fab")
			(hide yes)
			(effects
				(font
					(size 1.016 1.016)
					(thickness 0.1524)
				)
			)
		)
		(duplicate_pad_numbers_are_jumpers no)
		(fp_line
			(start 0.508 -0.9398)
			(end -0.508 -0.9398)
			(stroke
				(width 0.1524)
				(type default)
			)
			(layer "F.SilkS")
		)
		(fp_line
			(start -0.508 -0.9398)
			(end -0.508 0.9398)
			(stroke
				(width 0.1524)
				(type default)
			)
			(layer "F.SilkS")
		)
		(fp_rect
			(start -0.508 0.9398)
			(end 0.508 -0.9398)
			(stroke
				(width 0)
				(type default)
			)
			(fill no)
			(layer "F.CrtYd")
		)
		(fp_rect
			(start -0.508 0.9398)
			(end 0.508 -0.9398)
			(stroke
				(width 0)
				(type default)
			)
			(fill no)
			(layer "F.Fab")
		)
		(pad "1" smd custom
			(at 0 -0.4445 90)
			(size 0.1397 0.1397)
			(layers "F.Cu" "F.Mask" "F.Paste")
			(net "P3V3_STBY")
			(options
				(clearance outline)
				(anchor circle)
			)
			(primitives
				(gr_poly
					(pts
						(arc
							(start -0.1778 -0.2794)
							(mid -0.249642 -0.249642)
							(end -0.2794 -0.1778)
						)
						(arc
							(start -0.2794 0.1778)
							(mid -0.249642 0.249642)
							(end -0.1778 0.2794)
						)
						(arc
							(start 0.1778 0.2794)
							(mid 0.249642 0.249642)
							(end 0.2794 0.1778)
						)
						(arc
							(start 0.2794 -0.1778)
							(mid 0.249642 -0.249642)
							(end 0.1778 -0.2794)
						)
					)
					(width 0)
					(fill yes)
				)
			)
		)
		(pad "2" smd custom
			(at 0 0.4445 90)
			(size 0.1397 0.1397)
			(layers "F.Cu" "F.Mask" "F.Paste")
			(net "P0V9_E_PG")
			(options
				(clearance outline)
				(anchor circle)
			)
			(primitives
				(gr_poly
					(pts
						(arc
							(start -0.1778 -0.2794)
							(mid -0.249642 -0.249642)
							(end -0.2794 -0.1778)
						)
						(arc
							(start -0.2794 0.1778)
							(mid -0.249642 0.249642)
							(end -0.1778 0.2794)
						)
						(arc
							(start 0.1778 0.2794)
							(mid 0.249642 0.249642)
							(end 0.2794 0.1778)
						)
						(arc
							(start 0.2794 -0.1778)
							(mid 0.249642 -0.249642)
							(end 0.1778 -0.2794)
						)
					)
					(width 0)
					(fill yes)
				)
			)
		)
	)
	(footprint ""
		(layer "F.Cu")
		(at 331.597 -143.383 -90)
		(property "Reference" "C317"
			(at 0 0 270)
			(layer "F.SilkS")
			(hide yes)
			(effects
				(font
					(size 1.27 1.27)
				)
			)
		)
		(property "Value" "SC1U6D3V3KX-2GP"
			(at 0 -2.8194 270)
			(unlocked yes)
			(layer "F.Fab")
			(hide yes)
			(effects
				(font
					(size 1.016 1.016)
					(thickness 0.1524)
				)
			)
		)
		(property "Device Type" "C603H36"
			(at 0 -4.3434 270)
			(unlocked yes)
			(layer "F.Fab")
			(hide yes)
			(effects
				(font
					(size 1.016 1.016)
					(thickness 0.1524)
				)
			)
		)
		(duplicate_pad_numbers_are_jumpers no)
		(fp_line
			(start 0.508 0)
			(end -0.508 0)
			(stroke
				(width 0.2032)
				(type default)
			)
			(layer "F.SilkS")
		)
		(fp_rect
			(start -0.5842 1.3335)
			(end 0.5842 -1.3335)
			(stroke
				(width 0)
				(type default)
			)
			(fill no)
			(layer "F.CrtYd")
		)
		(fp_rect
			(start -0.5842 1.3335)
			(end 0.5842 -1.3335)
			(stroke
				(width 0)
				(type default)
			)
			(fill no)
			(layer "F.Fab")
		)
		(pad "1" smd custom
			(at 0 -0.762 270)
			(size 0.2159 0.2159)
			(layers "F.Cu" "F.Mask" "F.Paste")
			(net "P3V3_STBY")
			(options
				(clearance outline)
				(anchor circle)
			)
			(primitives
				(gr_poly
					(pts
						(arc
							(start -0.3302 -0.4318)
							(mid -0.402042 -0.402042)
							(end -0.4318 -0.3302)
						)
						(arc
							(start -0.4318 0.3302)
							(mid -0.402042 0.402042)
							(end -0.3302 0.4318)
						)
						(arc
							(start 0.3302 0.4318)
							(mid 0.402042 0.402042)
							(end 0.4318 0.3302)
						)
						(arc
							(start 0.4318 -0.3302)
							(mid 0.402042 -0.402042)
							(end 0.3302 -0.4318)
						)
					)
					(width 0)
					(fill yes)
				)
			)
		)
		(pad "2" smd custom
			(at 0 0.762 270)
			(size 0.2159 0.2159)
			(layers "F.Cu" "F.Mask" "F.Paste")
			(net "GND")
			(options
				(clearance outline)
				(anchor circle)
			)
			(primitives
				(gr_poly
					(pts
						(arc
							(start -0.3302 -0.4318)
							(mid -0.402042 -0.402042)
							(end -0.4318 -0.3302)
						)
						(arc
							(start -0.4318 0.3302)
							(mid -0.402042 0.402042)
							(end -0.3302 0.4318)
						)
						(arc
							(start 0.3302 0.4318)
							(mid 0.402042 0.402042)
							(end 0.4318 0.3302)
						)
						(arc
							(start 0.4318 -0.3302)
							(mid 0.402042 -0.402042)
							(end 0.3302 -0.4318)
						)
					)
					(width 0)
					(fill yes)
				)
			)
		)
	)
)
